# BASEBOARD_FAB2 (Tioga Pass) — schematic netlist excerpt (pin names and nets, part order shuffled) for the footprints in the layout excerpt that follows; sources: Cadence DE-HDL packaged netlist, KiCad conversion of Wiwynn_Tioga_Pass_MB.brd

C3B1  CAP  10UF 4V 20% X6S  pkg 0603LF  page 234 : A = PVPP_KLM ; B = GND
C4D28  CAP  0.220UF 16V 10% X7R  pkg 0402  page 203 : A = VR_PVCCIN_CPU0_PH3_BOOT ; B = VR_PVCCIN_CPU0_PH3_PHASE
C4E29  CAPP  470UF 2.5V 20% ALUM  pkg 3018  page 193 : A = PVCCMCP_CPU1 ; B = GND

(kicad_pcb
	(version 20260206)
	(generator "pcbnew")
	(generator_version "10.0")
	(general
		(thickness 1.6)
		(legacy_teardrops no)
	)
	(paper "A4")
	(title_block
		(title "Wiwynn_Tioga_Pass_MB.brd")
		(comment 1 "Tioga Pass / footprints 678-680 of 4770")
	)
	(layers
		(0 "F.Cu" signal "TOP")
		(4 "In1.Cu" signal "L2GND")
		(6 "In2.Cu" signal "L3")
		(8 "In3.Cu" signal "L4GND")
		(10 "In4.Cu" signal "L5")
		(12 "In5.Cu" signal "L6GND")
		(14 "In6.Cu" signal "L7VCC")
		(16 "In7.Cu" signal "L8VCC")
		(18 "In8.Cu" signal "L9GND")
		(20 "In9.Cu" signal "L10")
		(22 "In10.Cu" signal "L11GND")
		(24 "In11.Cu" signal "L12")
		(26 "In12.Cu" signal "L13GND")
		(2 "B.Cu" signal "BOTTOM")
		(9 "F.Adhes" user "F.Adhesive")
		(11 "B.Adhes" user "B.Adhesive")
		(13 "F.Paste" user "Package Geometry/Pastemask Top")
		(15 "B.Paste" user "Package Geometry/Pastemask Bottom")
		(5 "F.SilkS" user "Ref Des/Silkscreen Top")
		(7 "B.SilkS" user "Ref Des/Silkscreen Bottom")
		(1 "F.Mask" user "Board Geometry/Soldermask Top")
		(3 "B.Mask" user "Board Geometry/Soldermask Bottom")
		(17 "Dwgs.User" user "User.Drawings")
		(19 "Cmts.User" user "User.Comments")
		(21 "Eco1.User" user "User.Eco1")
		(23 "Eco2.User" user "User.Eco2")
		(25 "Edge.Cuts" user "Board Geometry/Outline")
		(27 "Margin" user)
		(31 "F.CrtYd" user "Package Geometry/Place Bound Top")
		(29 "B.CrtYd" user "Package Geometry/Place Bound Bottom")
		(35 "F.Fab" user "Ref Des/Assembly Top")
		(33 "B.Fab" user "Ref Des/Assembly Bottom")
	)
	(footprint ""
		(layer "F.Cu")
		(at 153.5176 -130.3528 -90)
		(property "Reference" "C3B1"
			(at 0 0 270)
			(layer "F.SilkS")
			(hide yes)
			(effects
				(font
					(size 1.27 1.27)
				)
			)
		)
		(property "Value" ""
			(at 0 0 270)
			(layer "F.Fab")
			(effects
				(font
					(size 1.27 1.27)
				)
			)
		)
		(duplicate_pad_numbers_are_jumpers no)
		(fp_rect
			(start -0.4953 1.6002)
			(end 0.4953 -0.2032)
			(stroke
				(width 0)
				(type default)
			)
			(fill no)
			(layer "F.CrtYd")
		)
		(fp_line
			(start -0.4953 1.6002)
			(end -0.4953 -0.2032)
			(stroke
				(width 0.1)
				(type default)
			)
			(layer "F.Fab")
		)
		(fp_line
			(start 0.4953 1.6002)
			(end -0.4953 1.6002)
			(stroke
				(width 0.1)
				(type default)
			)
			(layer "F.Fab")
		)
		(fp_line
			(start -0.4953 -0.2032)
			(end 0.4953 -0.2032)
			(stroke
				(width 0.1)
				(type default)
			)
			(layer "F.Fab")
		)
		(fp_line
			(start 0.4953 -0.2032)
			(end 0.4953 1.6002)
			(stroke
				(width 0.1)
				(type default)
			)
			(layer "F.Fab")
		)
		(pad "1" smd rect
			(at 0 0 270)
			(size 0.762 0.889)
			(layers "F.Cu" "F.Mask" "F.Paste")
			(net "PVPP_KLM")
		)
		(pad "2" smd rect
			(at 0 1.397 270)
			(size 0.762 0.889)
			(layers "F.Cu" "F.Mask" "F.Paste")
			(net "GND")
		)
		(zone
			(layer "F.Cu")
			(hatch none 0.5)
			(connect_pads
				(clearance 0)
			)
			(min_thickness 0.25)
			(keepout
				(tracks not_allowed)
				(vias allowed)
				(pads allowed)
				(copperpour not_allowed)
				(footprints allowed)
			)
			(placement
				(enabled no)
				(sheetname "")
			)
			(fill
				(thermal_gap 0.5)
				(thermal_bridge_width 0.5)
				(island_removal_mode 0)
			)
			(polygon
				(pts
					(xy 152.5651 -130.7338) (xy 152.5651 -129.9718) (xy 153.0731 -129.9718) (xy 153.0731 -130.7338)
				)
			)
		)
	)
	(footprint ""
		(layer "F.Cu")
		(at 193.9036 -75.1332 90)
		(property "Reference" "C4D28"
			(at 0 0 90)
			(layer "F.SilkS")
			(hide yes)
			(effects
				(font
					(size 1.27 1.27)
				)
			)
		)
		(property "Value" ""
			(at 0 0 90)
			(layer "F.Fab")
			(effects
				(font
					(size 1.27 1.27)
				)
			)
		)
		(duplicate_pad_numbers_are_jumpers no)
		(fp_rect
			(start -0.3048 0.9906)
			(end 0.3048 -0.1016)
			(stroke
				(width 0)
				(type default)
			)
			(fill no)
			(layer "F.CrtYd")
		)
		(fp_line
			(start 0.3048 -0.1016)
			(end -0.3048 -0.1016)
			(stroke
				(width 0.1)
				(type default)
			)
			(layer "F.Fab")
		)
		(fp_line
			(start -0.3048 -0.1016)
			(end -0.3048 0.9906)
			(stroke
				(width 0.1)
				(type default)
			)
			(layer "F.Fab")
		)
		(fp_line
			(start 0.3048 0.9906)
			(end 0.3048 -0.1016)
			(stroke
				(width 0.1)
				(type default)
			)
			(layer "F.Fab")
		)
		(fp_line
			(start -0.3048 0.9906)
			(end 0.3048 0.9906)
			(stroke
				(width 0.1)
				(type default)
			)
			(layer "F.Fab")
		)
		(pad "1" smd rect
			(at 0 0 90)
			(size 0.508 0.508)
			(layers "F.Cu" "F.Mask" "F.Paste")
			(net "VR_PVCCIN_CPU0_PH3_BOOT")
		)
		(pad "2" smd rect
			(at 0 0.889 90)
			(size 0.508 0.508)
			(layers "F.Cu" "F.Mask" "F.Paste")
			(net "VR_PVCCIN_CPU0_PH3_PHASE")
		)
		(zone
			(layer "F.Cu")
			(hatch none 0.5)
			(connect_pads
				(clearance 0)
			)
			(min_thickness 0.25)
			(keepout
				(tracks allowed)
				(vias not_allowed)
				(pads allowed)
				(copperpour not_allowed)
				(footprints allowed)
			)
			(placement
				(enabled no)
				(sheetname "")
			)
			(fill
				(thermal_gap 0.5)
				(thermal_bridge_width 0.5)
				(island_removal_mode 0)
			)
			(polygon
				(pts
					(xy 194.5386 -74.8792) (xy 194.5386 -75.3872) (xy 194.1576 -75.3872) (xy 194.1576 -74.8792)
				)
			)
		)
		(zone
			(layer "F.Cu")
			(hatch none 0.5)
			(connect_pads
				(clearance 0)
			)
			(min_thickness 0.25)
			(keepout
				(tracks not_allowed)
				(vias allowed)
				(pads allowed)
				(copperpour not_allowed)
				(footprints allowed)
			)
			(placement
				(enabled no)
				(sheetname "")
			)
			(fill
				(thermal_gap 0.5)
				(thermal_bridge_width 0.5)
				(island_removal_mode 0)
			)
			(polygon
				(pts
					(xy 194.5386 -74.8792) (xy 194.5386 -75.3872) (xy 194.1576 -75.3872) (xy 194.1576 -74.8792)
				)
			)
		)
	)
	(footprint ""
		(layer "F.Cu")
		(at 163.449 -47.879 90)
		(property "Reference" "C4E29"
			(at 2.92862 3.24612 0)
			(unlocked yes)
			(layer "F.SilkS")
			(effects
				(font
					(size 0.4064 0.254)
					(thickness 0.1524)
				)
			)
		)
		(property "Value" ""
			(at 0 0 90)
			(layer "F.Fab")
			(effects
				(font
					(size 1.27 1.27)
				)
			)
		)
		(duplicate_pad_numbers_are_jumpers no)
		(fp_line
			(start 2.504948 -1.616456)
			(end 2.504948 1.633728)
			(stroke
				(width 0.1524)
				(type default)
			)
			(layer "F.SilkS")
		)
		(fp_line
			(start 1.6002 -1.616456)
			(end 2.504948 -1.616456)
			(stroke
				(width 0.1524)
				(type default)
			)
			(layer "F.SilkS")
		)
		(fp_line
			(start -1.6002 -1.616456)
			(end -2.563114 -1.616456)
			(stroke
				(width 0.1524)
				(type default)
			)
			(layer "F.SilkS")
		)
		(fp_line
			(start -2.563114 -1.616456)
			(end -2.563114 1.633728)
			(stroke
				(width 0.1524)
				(type default)
			)
			(layer "F.SilkS")
		)
		(fp_line
			(start 2.504948 1.633728)
			(end 1.6002 1.633728)
			(stroke
				(width 0.1524)
				(type default)
			)
			(layer "F.SilkS")
		)
		(fp_line
			(start -2.563114 1.633728)
			(end -1.6002 1.633728)
			(stroke
				(width 0.1524)
				(type default)
			)
			(layer "F.SilkS")
		)
		(fp_line
			(start 2.286 7.366)
			(end 2.286 1.63195)
			(stroke
				(width 0.1524)
				(type default)
			)
			(layer "F.SilkS")
		)
		(fp_line
			(start 2.286 7.366)
			(end 1.600708 7.366)
			(stroke
				(width 0.1524)
				(type default)
			)
			(layer "F.SilkS")
		)
		(fp_line
			(start -2.286 7.366)
			(end -2.286 1.632712)
			(stroke
				(width 0.1524)
				(type default)
			)
			(layer "F.SilkS")
		)
		(fp_line
			(start -2.286 7.366)
			(end -1.60147 7.366)
			(stroke
				(width 0.1524)
				(type default)
			)
			(layer "F.SilkS")
		)
		(fp_rect
			(start -2.286 7.366)
			(end 2.286 -0.254)
			(stroke
				(width 0)
				(type default)
			)
			(fill no)
			(layer "F.CrtYd")
		)
		(fp_line
			(start 2.286 -0.254)
			(end 2.286 7.366)
			(stroke
				(width 0.1)
				(type default)
			)
			(layer "F.Fab")
		)
		(fp_line
			(start -2.286 -0.254)
			(end 2.286 -0.254)
			(stroke
				(width 0.1)
				(type default)
			)
			(layer "F.Fab")
		)
		(fp_line
			(start 2.286 7.366)
			(end -2.286 7.366)
			(stroke
				(width 0.1)
				(type default)
			)
			(layer "F.Fab")
		)
		(fp_line
			(start -2.286 7.366)
			(end -2.286 -0.254)
			(stroke
				(width 0.1)
				(type default)
			)
			(layer "F.Fab")
		)
		(pad "1" smd rect
			(at 0 0 90)
			(size 2.54 3.048)
			(layers "F.Cu" "F.Mask" "F.Paste")
			(net "PVCCMCP_CPU1")
		)
		(pad "2" smd rect
			(at 0 7.112 90)
			(size 2.54 3.048)
			(layers "F.Cu" "F.Mask" "F.Paste")
			(net "GND")
		)
	)
)
